# T6G (Grand Teton) — schematic netlist excerpt (pin names and nets, part order shuffled) for the footprints in the layout excerpt that follows; sources: Cadence DE-HDL packaged netlist, KiCad conversion of 04192023_DAF0TMB3IC0_F0TG_MB_C_brd_V02_OCP.brd

J121  PICOPROBE_BXA  DELTA-L 4.0 EMPTY  pkg TRIANG_LAUNCH_3PXB  page 229
  \1_p\  = DELTA_L_85_10INCH_IN6_DN
  \2_n\  = DELTA_L_85_10INCH_IN6_DP
  \3_g\  = DELTA_L_GND_1

(kicad_pcb
	(version 20260206)
	(generator "pcbnew")
	(generator_version "10.0")
	(general
		(thickness 1.6)
		(legacy_teardrops no)
	)
	(paper "A4")
	(title_block
		(title "04192023_DAF0TMB3IC0_F0TG_MB_C_brd_V02_OCP.brd")
		(comment 1 "Grand Teton / footprints 5390-5390 of 8354")
	)
	(layers
		(0 "F.Cu" signal "TOP")
		(4 "In1.Cu" signal "GND")
		(6 "In2.Cu" signal "IN1")
		(8 "In3.Cu" signal "GND1")
		(10 "In4.Cu" signal "IN2")
		(12 "In5.Cu" signal "GND2")
		(14 "In6.Cu" signal "IN3")
		(16 "In7.Cu" signal "GND3")
		(18 "In8.Cu" signal "VCC")
		(20 "In9.Cu" signal "VCC1")
		(22 "In10.Cu" signal "GND4")
		(24 "In11.Cu" signal "IN4")
		(26 "In12.Cu" signal "GND5")
		(28 "In13.Cu" signal "IN5")
		(30 "In14.Cu" signal "GND6")
		(32 "In15.Cu" signal "IN6")
		(34 "In16.Cu" signal "GND7")
		(2 "B.Cu" signal "BOTTOM")
		(9 "F.Adhes" user "F.Adhesive")
		(11 "B.Adhes" user "B.Adhesive")
		(13 "F.Paste" user "Package Geometry/Pastemask Top")
		(15 "B.Paste" user "Package Geometry/Pastemask Bottom")
		(5 "F.SilkS" user "Ref Des/Silkscreen Top")
		(7 "B.SilkS" user "Ref Des/Silkscreen Bottom")
		(1 "F.Mask" user "Board Geometry/Soldermask Top")
		(3 "B.Mask" user "Board Geometry/Soldermask Bottom")
		(17 "Dwgs.User" user "User.Drawings")
		(19 "Cmts.User" user "User.Comments")
		(21 "Eco1.User" user "User.Eco1")
		(23 "Eco2.User" user "User.Eco2")
		(25 "Edge.Cuts" user "Board Geometry/Outline")
		(27 "Margin" user)
		(31 "F.CrtYd" user "Package Geometry/Place Bound Top")
		(29 "B.CrtYd" user "Package Geometry/Place Bound Bottom")
		(35 "F.Fab" user "Ref Des/Assembly Top")
		(33 "B.Fab" user "Ref Des/Assembly Bottom")
	)
	(footprint ""
		(layer "B.Cu")
		(at 212.471508 2.542794 180)
		(property "Reference" "J121"
			(at 4.540504 -1.317498 270)
			(unlocked yes)
			(layer "B.SilkS")
			(effects
				(font
					(size 0.7874 0.5842)
					(thickness 0.1524)
				)
				(justify left mirror)
			)
		)
		(property "Value" ""
			(at 0 0 0)
			(layer "B.Fab")
			(effects
				(font
					(size 1.27 1.27)
				)
				(justify mirror)
			)
		)
		(duplicate_pad_numbers_are_jumpers no)
		(fp_line
			(start 1.2192 2.06756)
			(end 1.2192 -2.06756)
			(stroke
				(width 0.1524)
				(type default)
			)
			(layer "B.SilkS")
		)
		(fp_line
			(start 1.2192 -2.06756)
			(end -1.2192 -2.06756)
			(stroke
				(width 0.1524)
				(type default)
			)
			(layer "B.SilkS")
		)
		(fp_line
			(start -1.2192 2.06756)
			(end 1.2192 2.06756)
			(stroke
				(width 0.1524)
				(type default)
			)
			(layer "B.SilkS")
		)
		(fp_line
			(start -1.2192 -2.06756)
			(end -1.2192 2.06756)
			(stroke
				(width 0.1524)
				(type default)
			)
			(layer "B.SilkS")
		)
		(pad "" np_thru_hole circle
			(at -3.4671 -1.27 90)
			(size 1.0414 1.0414)
			(drill 1.0414)
			(layers "*.Cu" "*.Mask")
			(clearance 0.381)
			(thermal_gap 0.381)
		)
		(pad "" np_thru_hole circle
			(at -3.4671 1.27 90)
			(size 1.0414 1.0414)
			(drill 1.0414)
			(layers "*.Cu" "*.Mask")
			(clearance 0.381)
			(thermal_gap 0.381)
		)
		(pad "" np_thru_hole circle
			(at 2.8829 -1.27 90)
			(size 1.0414 1.0414)
			(drill 1.0414)
			(layers "*.Cu" "*.Mask")
			(clearance 0.381)
			(thermal_gap 0.381)
		)
		(pad "" np_thru_hole circle
			(at 2.8829 1.27 90)
			(size 1.0414 1.0414)
			(drill 1.0414)
			(layers "*.Cu" "*.Mask")
			(clearance 0.381)
			(thermal_gap 0.381)
		)
		(pad "1" smd rect
			(at -0.8255 -0.249936 90)
			(size 0.3048 0.508)
			(layers "B.Cu" "B.Mask" "B.Paste")
			(net "DELTA_L_85_10INCH_IN6_DN")
		)
		(pad "2" smd rect
			(at -0.8255 0.249936 90)
			(size 0.3048 0.508)
			(layers "B.Cu" "B.Mask" "B.Paste")
			(net "DELTA_L_85_10INCH_IN6_DP")
		)
		(pad "3" smd circle
			(at 0 0)
			(size 0 0)
			(layers "B.Cu" "B.Mask" "B.Paste")
			(net "DELTA_L_GND_1")
		)
		(zone
			(layers "F.Cu" "B.Cu" "In1.Cu" "In2.Cu" "In3.Cu" "In4.Cu" "In5.Cu" "In6.Cu"
				"In7.Cu" "In8.Cu" "In9.Cu" "In10.Cu" "In11.Cu" "In12.Cu" "In13.Cu" "In14.Cu"
				"In15.Cu" "In16.Cu"
			)
			(hatch none 0.5)
			(connect_pads
				(clearance 0)
			)
			(min_thickness 0.25)
			(keepout
				(tracks not_allowed)
				(vias allowed)
				(pads allowed)
				(copperpour not_allowed)
				(footprints allowed)
			)
			(placement
				(enabled no)
				(sheetname "")
			)
			(fill
				(thermal_gap 0.5)
				(thermal_bridge_width 0.5)
				(island_removal_mode 0)
			)
			(polygon
				(pts
					(arc
						(start 210.515708 1.272794)
						(mid 208.661508 1.272794)
						(end 210.515708 1.272794)
					)
				)
			)
		)
		(zone
			(layers "F.Cu" "B.Cu" "In1.Cu" "In2.Cu" "In3.Cu" "In4.Cu" "In5.Cu" "In6.Cu"
				"In7.Cu" "In8.Cu" "In9.Cu" "In10.Cu" "In11.Cu" "In12.Cu" "In13.Cu" "In14.Cu"
				"In15.Cu" "In16.Cu"
			)
			(hatch none 0.5)
			(connect_pads
				(clearance 0)
			)
			(min_thickness 0.25)
			(keepout
				(tracks not_allowed)
				(vias allowed)
				(pads allowed)
				(copperpour not_allowed)
				(footprints allowed)
			)
			(placement
				(enabled no)
				(sheetname "")
			)
			(fill
				(thermal_gap 0.5)
				(thermal_bridge_width 0.5)
				(island_removal_mode 0)
			)
			(polygon
				(pts
					(arc
						(start 210.515708 3.812794)
						(mid 208.661508 3.812794)
						(end 210.515708 3.812794)
					)
				)
			)
		)
		(zone
			(layers "F.Cu" "B.Cu" "In1.Cu" "In2.Cu" "In3.Cu" "In4.Cu" "In5.Cu" "In6.Cu"
				"In7.Cu" "In8.Cu" "In9.Cu" "In10.Cu" "In11.Cu" "In12.Cu" "In13.Cu" "In14.Cu"
				"In15.Cu" "In16.Cu"
			)
			(hatch none 0.5)
			(connect_pads
				(clearance 0)
			)
			(min_thickness 0.25)
			(keepout
				(tracks not_allowed)
				(vias allowed)
				(pads allowed)
				(copperpour not_allowed)
				(footprints allowed)
			)
			(placement
				(enabled no)
				(sheetname "")
			)
			(fill
				(thermal_gap 0.5)
				(thermal_bridge_width 0.5)
				(island_removal_mode 0)
			)
			(polygon
				(pts
					(arc
						(start 216.865708 1.272794)
						(mid 215.011508 1.272794)
						(end 216.865708 1.272794)
					)
				)
			)
		)
		(zone
			(layers "F.Cu" "B.Cu" "In1.Cu" "In2.Cu" "In3.Cu" "In4.Cu" "In5.Cu" "In6.Cu"
				"In7.Cu" "In8.Cu" "In9.Cu" "In10.Cu" "In11.Cu" "In12.Cu" "In13.Cu" "In14.Cu"
				"In15.Cu" "In16.Cu"
			)
			(hatch none 0.5)
			(connect_pads
				(clearance 0)
			)
			(min_thickness 0.25)
			(keepout
				(tracks not_allowed)
				(vias allowed)
				(pads allowed)
				(copperpour not_allowed)
				(footprints allowed)
			)
			(placement
				(enabled no)
				(sheetname "")
			)
			(fill
				(thermal_gap 0.5)
				(thermal_bridge_width 0.5)
				(island_removal_mode 0)
			)
			(polygon
				(pts
					(arc
						(start 216.865708 3.812794)
						(mid 215.011508 3.812794)
						(end 216.865708 3.812794)
					)
				)
			)
		)
		(zone
			(layer "B.Cu")
			(hatch none 0.5)
			(connect_pads
				(clearance 0)
			)
			(min_thickness 0.25)
			(keepout
				(tracks not_allowed)
				(vias allowed)
				(pads allowed)
				(copperpour not_allowed)
				(footprints allowed)
			)
			(placement
				(enabled no)
				(sheetname "")
			)
			(fill
				(thermal_gap 0.5)
				(thermal_bridge_width 0.5)
				(island_removal_mode 0)
			)
			(polygon
				(pts
					(xy 213.589108 3.091434) (xy 213.589108 2.99593) (xy 212.992208 2.99593) (xy 212.992208 2.58953)
					(xy 213.589108 2.58953) (xy 213.589108 2.496058) (xy 212.992208 2.496058) (xy 212.992208 2.089658)
					(xy 213.589108 2.089658) (xy 213.589108 1.994154) (xy 212.890608 1.994154) (xy 212.890608 3.091434)
				)
			)
		)
	)
)
